(kicad_pcb
	(version 20241229)
	(generator "pcbnew")
	(generator_version "9.0")
	(general
		(thickness 1.6296)
		(legacy_teardrops no)
	)
	(paper "A3")
	(title_block
		(title "Thunderbolt to 10GbE adapter")
		(date "2026-04-21")
		(rev "1.1.0")
		(company "Antmicro Ltd")
		(comment 1 "www.antmicro.com")
		(comment 9 "footprints 18-22 of 703")
	)
	(layers
		(0 "F.Cu" signal)
		(4 "In1.Cu" signal)
		(6 "In2.Cu" signal)
		(8 "In3.Cu" signal)
		(10 "In4.Cu" signal)
		(12 "In5.Cu" signal)
		(14 "In6.Cu" signal)
		(2 "B.Cu" signal)
		(9 "F.Adhes" user "F.Adhesive")
		(11 "B.Adhes" user "B.Adhesive")
		(13 "F.Paste" user)
		(15 "B.Paste" user)
		(5 "F.SilkS" user "F.Silkscreen")
		(7 "B.SilkS" user "B.Silkscreen")
		(1 "F.Mask" user)
		(3 "B.Mask" user)
		(17 "Dwgs.User" user "User.Drawings")
		(19 "Cmts.User" user "User.Comments")
		(21 "Eco1.User" user "User.Eco1")
		(23 "Eco2.User" user "User.Eco2")
		(25 "Edge.Cuts" user)
		(27 "Margin" user)
		(31 "F.CrtYd" user "F.Courtyard")
		(29 "B.CrtYd" user "B.Courtyard")
		(35 "F.Fab" user)
		(33 "B.Fab" user)
	)
	(footprint "antmicro-footprints:C_0402_1005Metric"
		(layer "F.Cu")
		(at 158.944999 96.954999 90)
		(descr "Capacitor SMD 0402")
		(tags "capacitor SMD 0402")
		(property "Reference" "C280"
			(at -19.625001 23.294999 90)
			(layer "F.SilkS")
			(effects
				(font
					(size 0.7 0.7)
					(thickness 0.15)
				)
			)
		)
		(property "Value" "C_5p6_0402"
			(at -1.022927 2.155213 90)
			(layer "F.Fab")
			(effects
				(font
					(size 0.7 0.7)
					(thickness 0.15)
				)
				(justify left bottom)
			)
		)
		(property "Datasheet" "https://www.mouser.com/datasheet/3/76/2/GCM1555C1H5R6BA16_01A.pdf"
			(at 0 0 90)
			(layer "F.Fab")
			(hide yes)
			(effects
				(font
					(size 1.27 1.27)
					(thickness 0.15)
				)
			)
		)
		(property "Description" "Multilayer Ceramic Capacitors MLCC - SMD/SMT 5.6 pF 50 VDC 0.1 pF 0402 C0G (NP0) AEC-Q200"
			(at 0 0 90)
			(layer "F.Fab")
			(hide yes)
			(effects
				(font
					(size 1.27 1.27)
					(thickness 0.15)
				)
			)
		)
		(property "MPN" "GCM1555C1H5R6BA16D"
			(at 0 0 90)
			(unlocked yes)
			(layer "F.Fab")
			(hide yes)
			(effects
				(font
					(size 1 1)
					(thickness 0.15)
				)
			)
		)
		(property "Manufacturer" "Murata"
			(at 0 0 90)
			(unlocked yes)
			(layer "F.Fab")
			(hide yes)
			(effects
				(font
					(size 1 1)
					(thickness 0.15)
				)
			)
		)
		(property "License" "Apache-2.0"
			(at 0 0 90)
			(unlocked yes)
			(layer "F.Fab")
			(hide yes)
			(effects
				(font
					(size 1 1)
					(thickness 0.15)
				)
			)
		)
		(property "Author" "Antmicro"
			(at 0 0 90)
			(unlocked yes)
			(layer "F.Fab")
			(hide yes)
			(effects
				(font
					(size 1 1)
					(thickness 0.15)
				)
			)
		)
		(property "Val" "5p6"
			(at 0 0 90)
			(unlocked yes)
			(layer "F.Fab")
			(hide yes)
			(effects
				(font
					(size 1 1)
					(thickness 0.15)
				)
			)
		)
		(property "Voltage" "50V"
			(at 0 0 90)
			(unlocked yes)
			(layer "F.Fab")
			(hide yes)
			(effects
				(font
					(size 1 1)
					(thickness 0.15)
				)
			)
		)
		(property "Dielectric" "C0G"
			(at 0 0 90)
			(unlocked yes)
			(layer "F.Fab")
			(hide yes)
			(effects
				(font
					(size 1 1)
					(thickness 0.15)
				)
			)
		)
		(sheetname "/X710-AT2 Misc/")
		(sheetfile "x710-at2-mics.kicad_sch")
		(attr smd)
		(fp_rect
			(start -0.925 -0.47)
			(end 0.925 0.47)
			(stroke
				(width 0.05)
				(type default)
			)
			(fill no)
			(layer "F.CrtYd")
		)
		(fp_line
			(start 0.504 -0.25)
			(end 0.504 0.248)
			(stroke
				(width 0.15)
				(type solid)
			)
			(layer "F.Fab")
		)
		(fp_line
			(start -0.494 -0.25)
			(end 0.504 -0.25)
			(stroke
				(width 0.15)
				(type solid)
			)
			(layer "F.Fab")
		)
		(fp_line
			(start 0.504 0.248)
			(end -0.494 0.248)
			(stroke
				(width 0.15)
				(type solid)
			)
			(layer "F.Fab")
		)
		(fp_line
			(start -0.494 0.248)
			(end -0.494 -0.25)
			(stroke
				(width 0.15)
				(type solid)
			)
			(layer "F.Fab")
		)
		(fp_text user "Author: Antmicro"
			(at -0.939 3.399 90)
			(layer "F.Fab")
			(effects
				(font
					(size 0.7 0.7)
					(thickness 0.15)
				)
				(justify left bottom)
			)
		)
		(fp_text user "${REFERENCE}"
			(at -0.939 4.599 90)
			(layer "F.Fab")
			(effects
				(font
					(size 0.7 0.7)
					(thickness 0.15)
				)
				(justify left bottom)
			)
		)
		(fp_text user "License: Apache-2.0"
			(at -0.939 5.799 90)
			(layer "F.Fab")
			(effects
				(font
					(size 0.7 0.7)
					(thickness 0.15)
				)
				(justify left bottom)
			)
		)
		(pad "1" smd roundrect
			(at -0.48 0 90)
			(size 0.59 0.64)
			(layers "F.Cu" "F.Mask" "F.Paste")
			(roundrect_rratio 0.25)
			(net 23 "GND")
			(pintype "passive")
		)
		(pad "2" smd roundrect
			(at 0.48 0 90)
			(size 0.59 0.64)
			(layers "F.Cu" "F.Mask" "F.Paste")
			(roundrect_rratio 0.25)
			(net 58 "/X710-AT2 Misc/50MHZ_XTAL_R.+")
			(pintype "passive")
		)
	)
	(footprint "antmicro-footprints:C_0603_1608Metric_EIA"
		(layer "F.Cu")
		(at 147.199999 113)
		(descr "Capacitor SMD 0603, IPC-7351 Density Level A")
		(tags "Capacitor 0603")
		(property "Reference" "C108"
			(at 14.850002 16.75 0)
			(layer "F.SilkS")
			(effects
				(font
					(size 0.7 0.7)
					(thickness 0.15)
				)
			)
		)
		(property "Value" "C_22u_16V_0603"
			(at -1.42757 1.770288 0)
			(layer "F.Fab")
			(effects
				(font
					(size 0.7 0.7)
					(thickness 0.15)
				)
				(justify left bottom)
			)
		)
		(property "Datasheet" "https://product.samsungsem.com/mlcc/CL10A226MO7JZN.do"
			(at 0 0 0)
			(layer "F.Fab")
			(hide yes)
			(effects
				(font
					(size 1.27 1.27)
					(thickness 0.15)
				)
			)
		)
		(property "Description" "SMD Multilayer Ceramic Capacitor"
			(at 0 0 0)
			(layer "F.Fab")
			(hide yes)
			(effects
				(font
					(size 1.27 1.27)
					(thickness 0.15)
				)
			)
		)
		(property "MPN" "CL10A226MO7JZNC"
			(at 0 0 0)
			(unlocked yes)
			(layer "F.Fab")
			(hide yes)
			(effects
				(font
					(size 1 1)
					(thickness 0.15)
				)
			)
		)
		(property "Manufacturer" "Samsung Electro-Mechanics"
			(at 0 0 0)
			(unlocked yes)
			(layer "F.Fab")
			(hide yes)
			(effects
				(font
					(size 1 1)
					(thickness 0.15)
				)
			)
		)
		(property "License" "Apache-2.0"
			(at 0 0 0)
			(unlocked yes)
			(layer "F.Fab")
			(hide yes)
			(effects
				(font
					(size 1 1)
					(thickness 0.15)
				)
			)
		)
		(property "Author" "Antmicro"
			(at 0 0 0)
			(unlocked yes)
			(layer "F.Fab")
			(hide yes)
			(effects
				(font
					(size 1 1)
					(thickness 0.15)
				)
			)
		)
		(property "Val" "22u"
			(at 0 0 0)
			(unlocked yes)
			(layer "F.Fab")
			(hide yes)
			(effects
				(font
					(size 1 1)
					(thickness 0.15)
				)
			)
		)
		(property "Voltage" "16V"
			(at 0 0 0)
			(unlocked yes)
			(layer "F.Fab")
			(hide yes)
			(effects
				(font
					(size 1 1)
					(thickness 0.15)
				)
			)
		)
		(property "Dielectric" ""
			(at 0 0 0)
			(unlocked yes)
			(layer "F.Fab")
			(hide yes)
			(effects
				(font
					(size 1 1)
					(thickness 0.15)
				)
			)
		)
		(sheetname "/X710 DCDC converters/")
		(sheetfile "DCDC_converters_X710.kicad_sch")
		(attr smd)
		(fp_line
			(start -0.15 -0.55)
			(end 0.15 -0.55)
			(stroke
				(width 0.15)
				(type solid)
			)
			(layer "F.SilkS")
		)
		(fp_line
			(start -0.15 0.55)
			(end 0.15 0.55)
			(stroke
				(width 0.15)
				(type solid)
			)
			(layer "F.SilkS")
		)
		(fp_rect
			(start -1.25 -0.65)
			(end 1.25 0.65)
			(stroke
				(width 0.05)
				(type solid)
			)
			(fill no)
			(layer "F.CrtYd")
		)
		(fp_rect
			(start -0.8 -0.45)
			(end 0.8 0.45)
			(stroke
				(width 0.15)
				(type solid)
			)
			(fill no)
			(layer "F.Fab")
		)
		(fp_text user "License: Apache-2.0"
			(at -1.682 5.895 0)
			(layer "F.Fab")
			(effects
				(font
					(size 0.7 0.7)
					(thickness 0.15)
				)
				(justify left bottom)
			)
		)
		(fp_text user "${REFERENCE}"
			(at -1.682 3.895 0)
			(layer "F.Fab")
			(effects
				(font
					(size 0.7 0.7)
					(thickness 0.15)
				)
				(justify left bottom)
			)
		)
		(fp_text user "Author: Antmicro"
			(at -1.682 4.894 0)
			(layer "F.Fab")
			(effects
				(font
					(size 0.7 0.7)
					(thickness 0.15)
				)
				(justify left bottom)
			)
		)
		(pad "1" smd roundrect
			(at -0.7 0)
			(size 0.8 1.1)
			(layers "F.Cu" "F.Mask" "F.Paste")
			(roundrect_rratio 0.2)
			(net 23 "GND")
			(pintype "passive")
		)
		(pad "2" smd roundrect
			(at 0.7 0)
			(size 0.8 1.1)
			(layers "F.Cu" "F.Mask" "F.Paste")
			(roundrect_rratio 0.2)
			(net 40 "+5V")
			(pintype "passive")
		)
	)
	(footprint "antmicro-footprints:C_0402_1005Metric"
		(layer "F.Cu")
		(at 122.2 102.1)
		(descr "Capacitor SMD 0402")
		(tags "capacitor SMD 0402")
		(property "Reference" "C18"
			(at -2 0 0)
			(layer "F.SilkS")
			(effects
				(font
					(size 0.7 0.7)
					(thickness 0.15)
				)
			)
		)
		(property "Value" "C_1u_25V_0402"
			(at -1.022927 2.155213 0)
			(layer "F.Fab")
			(effects
				(font
					(size 0.7 0.7)
					(thickness 0.15)
				)
				(justify left bottom)
			)
		)
		(property "Datasheet" "https://www.murata.com/products/productdetail?partno=GRM155R61E105KE11%23"
			(at 0 0 0)
			(layer "F.Fab")
			(hide yes)
			(effects
				(font
					(size 1.27 1.27)
					(thickness 0.15)
				)
			)
		)
		(property "Description" "SMD Multilayer Ceramic Capacitor, 1 µF, 25 V, 0402 [1005 Metric], ± 10%, X5R, GRM Series"
			(at 0 0 0)
			(layer "F.Fab")
			(hide yes)
			(effects
				(font
					(size 1.27 1.27)
					(thickness 0.15)
				)
			)
		)
		(property "MPN" "GRM155R61E105KE11J"
			(at 0 0 0)
			(unlocked yes)
			(layer "F.Fab")
			(hide yes)
			(effects
				(font
					(size 1 1)
					(thickness 0.15)
				)
			)
		)
		(property "Manufacturer" "Murata"
			(at 0 0 0)
			(unlocked yes)
			(layer "F.Fab")
			(hide yes)
			(effects
				(font
					(size 1 1)
					(thickness 0.15)
				)
			)
		)
		(property "License" "Apache-2.0"
			(at 0 0 0)
			(unlocked yes)
			(layer "F.Fab")
			(hide yes)
			(effects
				(font
					(size 1 1)
					(thickness 0.15)
				)
			)
		)
		(property "Author" "Antmicro"
			(at 0 0 0)
			(unlocked yes)
			(layer "F.Fab")
			(hide yes)
			(effects
				(font
					(size 1 1)
					(thickness 0.15)
				)
			)
		)
		(property "Val" "1u"
			(at 0 0 0)
			(unlocked yes)
			(layer "F.Fab")
			(hide yes)
			(effects
				(font
					(size 1 1)
					(thickness 0.15)
				)
			)
		)
		(property "Voltage" "25V"
			(at 0 0 0)
			(unlocked yes)
			(layer "F.Fab")
			(hide yes)
			(effects
				(font
					(size 1 1)
					(thickness 0.15)
				)
			)
		)
		(property "Dielectric" "X5R"
			(at 0 0 0)
			(unlocked yes)
			(layer "F.Fab")
			(hide yes)
			(effects
				(font
					(size 1 1)
					(thickness 0.15)
				)
			)
		)
		(sheetname "/PD and TB DC-DC/")
		(sheetfile "PD_and_TB_DC_DC.kicad_sch")
		(attr smd)
		(fp_rect
			(start -0.925 -0.47)
			(end 0.925 0.47)
			(stroke
				(width 0.05)
				(type default)
			)
			(fill no)
			(layer "F.CrtYd")
		)
		(fp_line
			(start -0.494 -0.25)
			(end 0.504 -0.25)
			(stroke
				(width 0.15)
				(type solid)
			)
			(layer "F.Fab")
		)
		(fp_line
			(start -0.494 0.248)
			(end -0.494 -0.25)
			(stroke
				(width 0.15)
				(type solid)
			)
			(layer "F.Fab")
		)
		(fp_line
			(start 0.504 -0.25)
			(end 0.504 0.248)
			(stroke
				(width 0.15)
				(type solid)
			)
			(layer "F.Fab")
		)
		(fp_line
			(start 0.504 0.248)
			(end -0.494 0.248)
			(stroke
				(width 0.15)
				(type solid)
			)
			(layer "F.Fab")
		)
		(fp_text user "${REFERENCE}"
			(at -0.939 4.599 0)
			(layer "F.Fab")
			(effects
				(font
					(size 0.7 0.7)
					(thickness 0.15)
				)
				(justify left bottom)
			)
		)
		(fp_text user "License: Apache-2.0"
			(at -0.939 5.799 0)
			(layer "F.Fab")
			(effects
				(font
					(size 0.7 0.7)
					(thickness 0.15)
				)
				(justify left bottom)
			)
		)
		(fp_text user "Author: Antmicro"
			(at -0.939 3.399 0)
			(layer "F.Fab")
			(effects
				(font
					(size 0.7 0.7)
					(thickness 0.15)
				)
				(justify left bottom)
			)
		)
		(pad "1" smd roundrect
			(at -0.48 0)
			(size 0.59 0.64)
			(layers "F.Cu" "F.Mask" "F.Paste")
			(roundrect_rratio 0.25)
			(net 23 "GND")
			(pintype "passive")
		)
		(pad "2" smd roundrect
			(at 0.48 0)
			(size 0.59 0.64)
			(layers "F.Cu" "F.Mask" "F.Paste")
			(roundrect_rratio 0.25)
			(net 399 "Net-(D4-A)")
			(pintype "passive")
		)
	)
	(footprint "antmicro-footprints:C_0402_1005Metric"
		(layer "F.Cu")
		(at 134.85 131.1 90)
		(descr "Capacitor SMD 0402")
		(tags "capacitor SMD 0402")
		(property "Reference" "C91"
			(at -0.170996 7.15 90)
			(layer "F.SilkS")
			(effects
				(font
					(size 0.7 0.7)
					(thickness 0.15)
				)
				(justify left bottom)
			)
		)
		(property "Value" "C_100n_0402"
			(at -1.022927 2.155213 90)
			(layer "F.Fab")
			(effects
				(font
					(size 0.7 0.7)
					(thickness 0.15)
				)
				(justify left bottom)
			)
		)
		(property "Datasheet" "https://www.murata.com/products/productdetail?partno=GRM155R61H104KE14%23"
			(at 0 0 90)
			(layer "F.Fab")
			(hide yes)
			(effects
				(font
					(size 1.27 1.27)
					(thickness 0.15)
				)
			)
		)
		(property "Description" "SMD Multilayer Ceramic Capacitor, 0.1 µF, 50 V, 0402 [1005 Metric], ± 10%, X5R, GRM Series"
			(at 0 0 90)
			(layer "F.Fab")
			(hide yes)
			(effects
				(font
					(size 1.27 1.27)
					(thickness 0.15)
				)
			)
		)
		(property "MPN" "GRM155R61H104KE14D"
			(at 0 0 90)
			(unlocked yes)
			(layer "F.Fab")
			(hide yes)
			(effects
				(font
					(size 1 1)
					(thickness 0.15)
				)
			)
		)
		(property "Manufacturer" "Murata"
			(at 0 0 90)
			(unlocked yes)
			(layer "F.Fab")
			(hide yes)
			(effects
				(font
					(size 1 1)
					(thickness 0.15)
				)
			)
		)
		(property "License" "Apache-2.0"
			(at 0 0 90)
			(unlocked yes)
			(layer "F.Fab")
			(hide yes)
			(effects
				(font
					(size 1 1)
					(thickness 0.15)
				)
			)
		)
		(property "Val" "100n"
			(at 0 0 90)
			(unlocked yes)
			(layer "F.Fab")
			(hide yes)
			(effects
				(font
					(size 1 1)
					(thickness 0.15)
				)
			)
		)
		(property "Voltage" "50V"
			(at 0 0 90)
			(unlocked yes)
			(layer "F.Fab")
			(hide yes)
			(effects
				(font
					(size 1 1)
					(thickness 0.15)
				)
			)
		)
		(property "Dielectric" "X5R"
			(at 0 0 90)
			(unlocked yes)
			(layer "F.Fab")
			(hide yes)
			(effects
				(font
					(size 1 1)
					(thickness 0.15)
				)
			)
		)
		(property "Author" "Antmicro"
			(at 0 0 90)
			(unlocked yes)
			(layer "F.Fab")
			(hide yes)
			(effects
				(font
					(size 1 1)
					(thickness 0.15)
				)
			)
		)
		(sheetname "/TB Controller - Power/")
		(sheetfile "tb-power.kicad_sch")
		(attr smd)
		(fp_rect
			(start -0.925 -0.47)
			(end 0.925 0.47)
			(stroke
				(width 0.05)
				(type default)
			)
			(fill no)
			(layer "F.CrtYd")
		)
		(fp_line
			(start 0.504 -0.25)
			(end 0.504 0.248)
			(stroke
				(width 0.15)
				(type solid)
			)
			(layer "F.Fab")
		)
		(fp_line
			(start -0.494 -0.25)
			(end 0.504 -0.25)
			(stroke
				(width 0.15)
				(type solid)
			)
			(layer "F.Fab")
		)
		(fp_line
			(start 0.504 0.248)
			(end -0.494 0.248)
			(stroke
				(width 0.15)
				(type solid)
			)
			(layer "F.Fab")
		)
		(fp_line
			(start -0.494 0.248)
			(end -0.494 -0.25)
			(stroke
				(width 0.15)
				(type solid)
			)
			(layer "F.Fab")
		)
		(fp_text user "${REFERENCE}"
			(at -0.939 4.599 90)
			(layer "F.Fab")
			(effects
				(font
					(size 0.7 0.7)
					(thickness 0.15)
				)
				(justify left bottom)
			)
		)
		(fp_text user "License: Apache-2.0"
			(at -0.939 5.799 90)
			(layer "F.Fab")
			(effects
				(font
					(size 0.7 0.7)
					(thickness 0.15)
				)
				(justify left bottom)
			)
		)
		(fp_text user "Author: Antmicro"
			(at -0.939 3.399 90)
			(layer "F.Fab")
			(effects
				(font
					(size 0.7 0.7)
					(thickness 0.15)
				)
				(justify left bottom)
			)
		)
		(pad "1" smd roundrect
			(at -0.48 0 90)
			(size 0.59 0.64)
			(layers "F.Cu" "F.Mask" "F.Paste")
			(roundrect_rratio 0.25)
			(net 23 "GND")
			(pintype "passive")
		)
		(pad "2" smd roundrect
			(at 0.48 0 90)
			(size 0.59 0.64)
			(layers "F.Cu" "F.Mask" "F.Paste")
			(roundrect_rratio 0.25)
			(net 57 "+3V3_TB")
			(pintype "passive")
		)
	)
	(footprint "antmicro-footprints:FB_0603_1608Metric"
		(layer "F.Cu")
		(at 164.105 99.224999 90)
		(property "Reference" "FB7"
			(at 0 7.695 90)
			(layer "F.SilkS")
			(effects
				(font
					(size 0.7 0.7)
					(thickness 0.15)
				)
			)
		)
		(property "Value" "FB_33Z_3A_Murata-BLM18PG_0603"
			(at 0 1.5 90)
			(layer "F.Fab")
			(effects
				(font
					(size 0.7 0.7)
					(thickness 0.15)
				)
				(justify left bottom)
			)
		)
		(property "Datasheet" "https://www.murata.com/products/productdata/8796737273886/QNFA9101.pdf?1649080818000"
			(at 0 0 90)
			(layer "F.Fab")
			(hide yes)
			(effects
				(font
					(size 1.27 1.27)
					(thickness 0.15)
				)
			)
		)
		(property "Description" "Ferrite Bead, 0603 [1608 Metric], 33 ohm, 3 A, BLM18PG, 0.025 ohm, ± 25%, DC power line"
			(at 0 0 90)
			(layer "F.Fab")
			(hide yes)
			(effects
				(font
					(size 1.27 1.27)
					(thickness 0.15)
				)
			)
		)
		(property "Val" "33Z/3A"
			(at 0 0 90)
			(unlocked yes)
			(layer "F.Fab")
			(hide yes)
			(effects
				(font
					(size 1 1)
					(thickness 0.15)
				)
			)
		)
		(property "MPN" "BLM18PG330SH1D"
			(at 0 0 90)
			(unlocked yes)
			(layer "F.Fab")
			(hide yes)
			(effects
				(font
					(size 1 1)
					(thickness 0.15)
				)
			)
		)
		(property "Manufacturer" "Murata"
			(at 0 0 90)
			(unlocked yes)
			(layer "F.Fab")
			(hide yes)
			(effects
				(font
					(size 1 1)
					(thickness 0.15)
				)
			)
		)
		(property "Current" ""
			(at 0 0 90)
			(unlocked yes)
			(layer "F.Fab")
			(hide yes)
			(effects
				(font
					(size 1 1)
					(thickness 0.15)
				)
			)
		)
		(property "Author" "Antmicro"
			(at 0 0 90)
			(unlocked yes)
			(layer "F.Fab")
			(hide yes)
			(effects
				(font
					(size 1 1)
					(thickness 0.15)
				)
			)
		)
		(property "License" "Apache-2.0"
			(at 0 0 90)
			(unlocked yes)
			(layer "F.Fab")
			(hide yes)
			(effects
				(font
					(size 1 1)
					(thickness 0.15)
				)
			)
		)
		(sheetname "/X710-AT2 power/")
		(sheetfile "x710-at2-power.kicad_sch")
		(attr smd)
		(fp_line
			(start -0.15 -0.4)
			(end 0.15 -0.4)
			(stroke
				(width 0.15)
				(type solid)
			)
			(layer "F.SilkS")
		)
		(fp_line
			(start -0.15 0.4)
			(end 0.15 0.4)
			(stroke
				(width 0.15)
				(type solid)
			)
			(layer "F.SilkS")
		)
		(fp_rect
			(start -1.25 -0.65)
			(end 1.25 0.65)
			(stroke
				(width 0.05)
				(type solid)
			)
			(fill no)
			(layer "F.CrtYd")
		)
		(fp_line
			(start 0.8 -0.408)
			(end -0.803 -0.408)
			(stroke
				(width 0.15)
				(type solid)
			)
			(layer "F.Fab")
		)
		(fp_line
			(start 0.8 -0.408)
			(end 0.8 0.406)
			(stroke
				(width 0.15)
				(type solid)
			)
			(layer "F.Fab")
		)
		(fp_line
			(start 0.8 0.406)
			(end -0.803 0.406)
			(stroke
				(width 0.15)
				(type solid)
			)
			(layer "F.Fab")
		)
		(fp_line
			(start -0.803 0.406)
			(end -0.803 -0.408)
			(stroke
				(width 0.15)
				(type solid)
			)
			(layer "F.Fab")
		)
		(fp_text user "Author: Antmicro"
			(at -1.653 3.162 90)
			(layer "F.Fab")
			(effects
				(font
					(size 0.7 0.7)
					(thickness 0.15)
				)
				(justify left bottom)
			)
		)
		(fp_text user "${REFERENCE}"
			(at -1.653 4.6 90)
			(layer "F.Fab")
			(effects
				(font
					(size 0.7 0.7)
					(thickness 0.15)
				)
				(justify left bottom)
			)
		)
		(fp_text user "License: Apache-2.0"
			(at -1.653 5.9 90)
			(layer "F.Fab")
			(effects
				(font
					(size 0.7 0.7)
					(thickness 0.15)
				)
				(justify left bottom)
			)
		)
		(pad "1" smd roundrect
			(at -0.7 0 90)
			(size 0.8 1)
			(layers "F.Cu" "F.Mask" "F.Paste")
			(roundrect_rratio 0.2)
			(net 136 "+1V0")
			(pintype "passive")
		)
		(pad "2" smd roundrect
			(at 0.7 0 90)
			(size 0.8 1)
			(layers "F.Cu" "F.Mask" "F.Paste")
			(roundrect_rratio 0.2)
			(net 14 "P1_AVDDL")
			(pintype "passive")
		)
	)
)
